(kicad_pcb
	(version 20260206)
	(generator "pcbnew")
	(generator_version "10.0")
	(general
		(thickness 1.6)
		(legacy_teardrops no)
	)
	(paper "A4")
	(title_block
		(title "01162023_DA0F0TEBIF0_F0T_Expander_BD_F_brd_V02_OCP.brd")
		(comment 1 "Grand Teton / footprints 390-394 of 9728")
	)
	(layers
		(0 "F.Cu" signal "TOP")
		(4 "In1.Cu" signal "GND")
		(6 "In2.Cu" signal "VCC")
		(8 "In3.Cu" signal "VCC1")
		(10 "In4.Cu" signal "GND1")
		(12 "In5.Cu" signal "IN1")
		(14 "In6.Cu" signal "GND2")
		(16 "In7.Cu" signal "IN2")
		(18 "In8.Cu" signal "GND3")
		(20 "In9.Cu" signal "IN3")
		(22 "In10.Cu" signal "GND4")
		(24 "In11.Cu" signal "IN4")
		(26 "In12.Cu" signal "GND5")
		(28 "In13.Cu" signal "IN5")
		(30 "In14.Cu" signal "GND6")
		(32 "In15.Cu" signal "IN6")
		(34 "In16.Cu" signal "GND7")
		(2 "B.Cu" signal "BOTTOM")
		(9 "F.Adhes" user "F.Adhesive")
		(11 "B.Adhes" user "B.Adhesive")
		(13 "F.Paste" user "Package Geometry/Pastemask Top")
		(15 "B.Paste" user "Package Geometry/Pastemask Bottom")
		(5 "F.SilkS" user "Ref Des/Silkscreen Top")
		(7 "B.SilkS" user "Ref Des/Silkscreen Bottom")
		(1 "F.Mask" user "Board Geometry/Soldermask Top")
		(3 "B.Mask" user "Board Geometry/Soldermask Bottom")
		(17 "Dwgs.User" user "User.Drawings")
		(19 "Cmts.User" user "User.Comments")
		(21 "Eco1.User" user "User.Eco1")
		(23 "Eco2.User" user "User.Eco2")
		(25 "Edge.Cuts" user "Board Geometry/Outline")
		(27 "Margin" user)
		(31 "F.CrtYd" user "Package Geometry/Place Bound Top")
		(29 "B.CrtYd" user "Package Geometry/Place Bound Bottom")
		(35 "F.Fab" user "Ref Des/Assembly Top")
		(33 "B.Fab" user "Ref Des/Assembly Bottom")
	)
	(footprint ""
		(layer "F.Cu")
		(at 223.445832 -102.356666 -90)
		(property "Reference" "PU28"
			(at 1.75641 2.251964 90)
			(unlocked yes)
			(layer "F.SilkS")
			(effects
				(font
					(size 0.7874 0.5842)
					(thickness 0.1524)
				)
				(justify left)
			)
		)
		(property "Value" ""
			(at 0 0 270)
			(layer "F.Fab")
			(effects
				(font
					(size 1.27 1.27)
				)
			)
		)
		(duplicate_pad_numbers_are_jumpers no)
		(fp_line
			(start -1.943608 1.549908)
			(end -1.943608 -1.549908)
			(stroke
				(width 0.1524)
				(type default)
			)
			(layer "F.SilkS")
		)
		(fp_line
			(start 1.943608 1.549908)
			(end -1.943608 1.549908)
			(stroke
				(width 0.1524)
				(type default)
			)
			(layer "F.SilkS")
		)
		(fp_line
			(start -1.943608 -1.549908)
			(end 1.943608 -1.549908)
			(stroke
				(width 0.1524)
				(type default)
			)
			(layer "F.SilkS")
		)
		(fp_line
			(start 1.943608 -1.549908)
			(end 1.943608 1.549908)
			(stroke
				(width 0.1524)
				(type default)
			)
			(layer "F.SilkS")
		)
		(fp_poly
			(pts
				(xy -2.019808 -1.549908) (xy -1.257808 -1.549908) (xy -1.257808 -1.880108) (xy -2.019808 -1.880108)
			)
			(stroke
				(width 0)
				(type default)
			)
			(fill yes)
			(layer "F.SilkS")
		)
		(fp_line
			(start -1.549908 1.549908)
			(end -1.549908 -1.549908)
			(stroke
				(width 0.1)
				(type default)
			)
			(layer "F.Fab")
		)
		(fp_line
			(start 1.549908 1.549908)
			(end -1.549908 1.549908)
			(stroke
				(width 0.1)
				(type default)
			)
			(layer "F.Fab")
		)
		(fp_line
			(start -1.549908 -1.549908)
			(end 1.549908 -1.549908)
			(stroke
				(width 0.1)
				(type default)
			)
			(layer "F.Fab")
		)
		(fp_line
			(start 1.549908 -1.549908)
			(end 1.549908 1.549908)
			(stroke
				(width 0.1)
				(type default)
			)
			(layer "F.Fab")
		)
		(fp_poly
			(pts
				(xy -2.019808 -1.549908) (xy -1.257808 -1.549908) (xy -1.257808 -1.880108) (xy -2.019808 -1.880108)
			)
			(stroke
				(width 0)
				(type default)
			)
			(fill yes)
			(layer "F.Fab")
		)
		(pad "1" smd rect
			(at -1.500124 -1.249934 180)
			(size 0.2794 0.6096)
			(layers "F.Cu" "F.Mask" "F.Paste")
			(net "P12V_NIC3_R")
		)
		(pad "2" smd rect
			(at -1.500124 -0.750062 180)
			(size 0.2794 0.6096)
			(layers "F.Cu" "F.Mask" "F.Paste")
			(net "P12V_NIC3_R")
		)
		(pad "3" smd rect
			(at -1.500124 -0.249936 180)
			(size 0.2794 0.6096)
			(layers "F.Cu" "F.Mask" "F.Paste")
			(net "P12V_NIC3_R")
		)
		(pad "4" smd rect
			(at -1.500124 0.249936 180)
			(size 0.2794 0.6096)
			(layers "F.Cu" "F.Mask" "F.Paste")
			(net "P12V_NIC3_R")
		)
		(pad "5" smd rect
			(at -1.500124 0.750062 180)
			(size 0.2794 0.6096)
			(layers "F.Cu" "F.Mask" "F.Paste")
			(net "P12V_NIC3_R")
		)
		(pad "6" smd rect
			(at -1.500124 1.249934 180)
			(size 0.2794 0.6096)
			(layers "F.Cu" "F.Mask" "F.Paste")
			(net "GND")
		)
		(pad "7" smd rect
			(at 1.500124 1.249934 180)
			(size 0.2794 0.6096)
			(layers "F.Cu" "F.Mask" "F.Paste")
			(net "P12V_NIC3_SS")
		)
		(pad "8" smd rect
			(at 1.500124 0.750062 180)
			(size 0.2794 0.6096)
			(layers "F.Cu" "F.Mask" "F.Paste")
			(net "PWRGD_P12V_NIC3")
		)
		(pad "9" smd rect
			(at 1.500124 0.249936 180)
			(size 0.2794 0.6096)
			(layers "F.Cu" "F.Mask" "F.Paste")
			(net "P12V_NIC3_OCP")
		)
		(pad "10" smd rect
			(at 1.500124 -0.249936 180)
			(size 0.2794 0.6096)
			(layers "F.Cu" "F.Mask" "F.Paste")
			(net "P5V_AUX")
		)
		(pad "11" smd rect
			(at 1.500124 -0.750062 180)
			(size 0.2794 0.6096)
			(layers "F.Cu" "F.Mask" "F.Paste")
			(net "P12V_NIC3_EN_R")
		)
		(pad "12" smd rect
			(at 1.500124 -1.249934 180)
			(size 0.2794 0.6096)
			(layers "F.Cu" "F.Mask" "F.Paste")
			(net "P12V_AUX")
		)
		(pad "13" smd rect
			(at 0 0 270)
			(size 1.9812 2.7178)
			(layers "F.Cu" "F.Mask" "F.Paste")
			(net "P12V_AUX")
		)
		(zone
			(layer "F.Cu")
			(hatch none 0.5)
			(connect_pads
				(clearance 0)
			)
			(min_thickness 0.25)
			(keepout
				(tracks not_allowed)
				(vias allowed)
				(pads allowed)
				(copperpour not_allowed)
				(footprints allowed)
			)
			(placement
				(enabled no)
				(sheetname "")
			)
			(fill
				(thermal_gap 0.5)
				(thermal_bridge_width 0.5)
				(island_removal_mode 0)
			)
			(polygon
				(pts
					(xy 224.995232 -101.213666) (xy 224.868232 -101.213666) (xy 221.896432 -101.213666) (xy 221.895924 -101.213666)
					(xy 221.895924 -103.499666) (xy 221.896432 -103.499666) (xy 222.023432 -103.499666) (xy 223.445832 -103.499666)
					(xy 223.445832 -103.398066) (xy 222.023432 -103.398066) (xy 222.023432 -101.315266) (xy 224.868232 -101.315266)
					(xy 224.868232 -103.398066) (xy 223.471232 -103.398066) (xy 223.471232 -103.499666) (xy 224.868232 -103.499666)
					(xy 224.995232 -103.499666) (xy 224.99574 -103.499666) (xy 224.99574 -101.213666)
				)
			)
		)
	)
	(footprint ""
		(layer "F.Cu")
		(at 346.075 -181.229)
		(property "Reference" "U347"
			(at -1.4478 -4.613148 0)
			(unlocked yes)
			(layer "F.SilkS")
			(effects
				(font
					(size 0.7874 0.5842)
					(thickness 0.1524)
				)
				(justify left)
			)
		)
		(property "Value" ""
			(at 0 0 0)
			(layer "F.Fab")
			(effects
				(font
					(size 1.27 1.27)
				)
			)
		)
		(duplicate_pad_numbers_are_jumpers no)
		(fp_line
			(start -2.097532 -3.949954)
			(end -2.097532 3.949954)
			(stroke
				(width 0.1524)
				(type default)
			)
			(layer "F.SilkS")
		)
		(fp_line
			(start -2.097532 3.949954)
			(end 2.097532 3.949954)
			(stroke
				(width 0.1524)
				(type default)
			)
			(layer "F.SilkS")
		)
		(fp_line
			(start -1.409954 -3.949954)
			(end -2.097532 -3.949954)
			(stroke
				(width 0.1524)
				(type default)
			)
			(layer "F.SilkS")
		)
		(fp_line
			(start 0 -2.54)
			(end -1.409954 -3.949954)
			(stroke
				(width 0.1524)
				(type default)
			)
			(layer "F.SilkS")
		)
		(fp_line
			(start 1.409954 -3.949954)
			(end 0 -2.54)
			(stroke
				(width 0.1524)
				(type default)
			)
			(layer "F.SilkS")
		)
		(fp_line
			(start 2.097532 -3.949954)
			(end 1.409954 -3.949954)
			(stroke
				(width 0.1524)
				(type default)
			)
			(layer "F.SilkS")
		)
		(fp_line
			(start 2.097532 3.949954)
			(end 2.097532 -3.949954)
			(stroke
				(width 0.1524)
				(type default)
			)
			(layer "F.SilkS")
		)
		(fp_poly
			(pts
				(xy -4.7498 -4.182872) (xy -4.7498 -3.166872) (xy -3.7338 -3.674872)
			)
			(stroke
				(width 0)
				(type default)
			)
			(fill yes)
			(layer "F.SilkS")
		)
		(fp_line
			(start -2.249932 -3.949954)
			(end -2.249932 3.949954)
			(stroke
				(width 0.1)
				(type default)
			)
			(layer "F.Fab")
		)
		(fp_line
			(start -2.249932 3.949954)
			(end 2.249932 3.949954)
			(stroke
				(width 0.1)
				(type default)
			)
			(layer "F.Fab")
		)
		(fp_line
			(start 2.249932 -3.949954)
			(end -2.249932 -3.949954)
			(stroke
				(width 0.1)
				(type default)
			)
			(layer "F.Fab")
		)
		(fp_line
			(start 2.249932 3.949954)
			(end 2.249932 -3.949954)
			(stroke
				(width 0.1)
				(type default)
			)
			(layer "F.Fab")
		)
		(fp_poly
			(pts
				(xy -4.7498 -4.182872) (xy -4.7498 -3.166872) (xy -3.7338 -3.674872)
			)
			(stroke
				(width 0)
				(type default)
			)
			(fill yes)
			(layer "F.Fab")
		)
		(pad "1" smd rect
			(at -2.925064 -3.674872 270)
			(size 0.6096 1.3716)
			(layers "F.Cu" "F.Mask" "F.Paste")
			(net "PEX2_PCA9555_0_INT_N")
		)
		(pad "2" smd rect
			(at -2.925064 -2.925064 270)
			(size 0.4064 1.3716)
			(layers "F.Cu" "F.Mask" "F.Paste")
			(net "PCA9555_0_PEX2_A1")
		)
		(pad "3" smd rect
			(at -2.925064 -2.275078 270)
			(size 0.4064 1.3716)
			(layers "F.Cu" "F.Mask" "F.Paste")
			(net "PCA9555_0_PEX2_A2")
		)
		(pad "4" smd rect
			(at -2.925064 -1.625092 270)
			(size 0.4064 1.3716)
			(layers "F.Cu" "F.Mask" "F.Paste")
			(net "PRSNT_SSD8_FPGA_PCA9555_N")
		)
		(pad "5" smd rect
			(at -2.925064 -0.975106 270)
			(size 0.4064 1.3716)
			(layers "F.Cu" "F.Mask" "F.Paste")
			(net "SSD8_PEX_PWR_EN")
		)
		(pad "6" smd rect
			(at -2.925064 -0.32512 270)
			(size 0.4064 1.3716)
			(layers "F.Cu" "F.Mask" "F.Paste")
			(net "RST_PEX_SSD8_PERST_N")
		)
		(pad "7" smd rect
			(at -2.925064 0.32512 270)
			(size 0.4064 1.3716)
			(layers "F.Cu" "F.Mask" "F.Paste")
			(net "Net_1175")
		)
		(pad "8" smd rect
			(at -2.925064 0.975106 270)
			(size 0.4064 1.3716)
			(layers "F.Cu" "F.Mask" "F.Paste")
			(net "PRSNT_SSD9_FPGA_PCA9555_N")
		)
		(pad "9" smd rect
			(at -2.925064 1.625092 270)
			(size 0.4064 1.3716)
			(layers "F.Cu" "F.Mask" "F.Paste")
			(net "SSD9_PEX_PWR_EN")
		)
		(pad "10" smd rect
			(at -2.925064 2.275078 270)
			(size 0.4064 1.3716)
			(layers "F.Cu" "F.Mask" "F.Paste")
			(net "RST_PEX_SSD9_PERST_N")
		)
		(pad "11" smd rect
			(at -2.925064 2.925064 270)
			(size 0.4064 1.3716)
			(layers "F.Cu" "F.Mask" "F.Paste")
			(net "Net_1176")
		)
		(pad "12" smd rect
			(at -2.925064 3.674872 270)
			(size 0.6096 1.3716)
			(layers "F.Cu" "F.Mask" "F.Paste")
			(net "GND")
		)
		(pad "13" smd rect
			(at 2.925064 3.674872 270)
			(size 0.6096 1.3716)
			(layers "F.Cu" "F.Mask" "F.Paste")
			(net "PRSNT_NIC4_FPGA_PCA9555_N")
		)
		(pad "14" smd rect
			(at 2.925064 2.925064 270)
			(size 0.4064 1.3716)
			(layers "F.Cu" "F.Mask" "F.Paste")
			(net "NIC4_PEX_PWR_EN")
		)
		(pad "15" smd rect
			(at 2.925064 2.275078 270)
			(size 0.4064 1.3716)
			(layers "F.Cu" "F.Mask" "F.Paste")
			(net "RST_PEX_NIC4_PERST_N")
		)
		(pad "16" smd rect
			(at 2.925064 1.625092 270)
			(size 0.4064 1.3716)
			(layers "F.Cu" "F.Mask" "F.Paste")
			(net "Net_1177")
		)
		(pad "17" smd rect
			(at 2.925064 0.975106 270)
			(size 0.4064 1.3716)
			(layers "F.Cu" "F.Mask" "F.Paste")
			(net "Net_8976")
		)
		(pad "18" smd rect
			(at 2.925064 0.32512 270)
			(size 0.4064 1.3716)
			(layers "F.Cu" "F.Mask" "F.Paste")
			(net "Net_8975")
		)
		(pad "19" smd rect
			(at 2.925064 -0.32512 270)
			(size 0.4064 1.3716)
			(layers "F.Cu" "F.Mask" "F.Paste")
			(net "Net_8974")
		)
		(pad "20" smd rect
			(at 2.925064 -0.975106 270)
			(size 0.4064 1.3716)
			(layers "F.Cu" "F.Mask" "F.Paste")
			(net "Net_8973")
		)
		(pad "21" smd rect
			(at 2.925064 -1.625092 270)
			(size 0.4064 1.3716)
			(layers "F.Cu" "F.Mask" "F.Paste")
			(net "PCA9555_0_PEX2_A0")
		)
		(pad "22" smd rect
			(at 2.925064 -2.275078 270)
			(size 0.4064 1.3716)
			(layers "F.Cu" "F.Mask" "F.Paste")
			(net "SMB_PEX2_PCA9555_SCL")
		)
		(pad "23" smd rect
			(at 2.925064 -2.925064 270)
			(size 0.4064 1.3716)
			(layers "F.Cu" "F.Mask" "F.Paste")
			(net "SMB_PEX2_PCA9555_SDA")
		)
		(pad "24" smd rect
			(at 2.925064 -3.674872 270)
			(size 0.6096 1.3716)
			(layers "F.Cu" "F.Mask" "F.Paste")
			(net "P3V3_AUX")
		)
	)
	(footprint ""
		(layer "F.Cu")
		(at 234.152694 -257.975862 -90)
		(property "Reference" "R6532"
			(at 0 0 270)
			(layer "F.SilkS")
			(hide yes)
			(effects
				(font
					(size 1.27 1.27)
				)
			)
		)
		(property "Value" ""
			(at 0 0 270)
			(layer "F.Fab")
			(effects
				(font
					(size 1.27 1.27)
				)
			)
		)
		(duplicate_pad_numbers_are_jumpers no)
		(fp_line
			(start -0.7874 0.4064)
			(end -0.7874 -0.4064)
			(stroke
				(width 0.1524)
				(type default)
			)
			(layer "F.SilkS")
		)
		(fp_line
			(start 0.7874 0.4064)
			(end -0.7874 0.4064)
			(stroke
				(width 0.1524)
				(type default)
			)
			(layer "F.SilkS")
		)
		(fp_line
			(start -0.7874 -0.4064)
			(end 0.7874 -0.4064)
			(stroke
				(width 0.1524)
				(type default)
			)
			(layer "F.SilkS")
		)
		(fp_line
			(start 0.7874 -0.4064)
			(end 0.7874 0.4064)
			(stroke
				(width 0.1524)
				(type default)
			)
			(layer "F.SilkS")
		)
		(fp_line
			(start -0.67945 0.3048)
			(end -0.67945 -0.305054)
			(stroke
				(width 0.1)
				(type default)
			)
			(layer "F.Fab")
		)
		(fp_line
			(start -0.12065 0.3048)
			(end -0.67945 0.3048)
			(stroke
				(width 0.1)
				(type default)
			)
			(layer "F.Fab")
		)
		(fp_line
			(start 0.120396 0.3048)
			(end 0.120396 0.2794)
			(stroke
				(width 0.1)
				(type default)
			)
			(layer "F.Fab")
		)
		(fp_line
			(start 0.67945 0.3048)
			(end 0.120396 0.3048)
			(stroke
				(width 0.1)
				(type default)
			)
			(layer "F.Fab")
		)
		(fp_line
			(start -0.12065 0.2794)
			(end -0.12065 0.3048)
			(stroke
				(width 0.1)
				(type default)
			)
			(layer "F.Fab")
		)
		(fp_line
			(start 0.120396 0.2794)
			(end -0.12065 0.2794)
			(stroke
				(width 0.1)
				(type default)
			)
			(layer "F.Fab")
		)
		(fp_line
			(start -0.12065 -0.2794)
			(end 0.12065 -0.2794)
			(stroke
				(width 0.1)
				(type default)
			)
			(layer "F.Fab")
		)
		(fp_line
			(start 0.12065 -0.2794)
			(end 0.12065 -0.3048)
			(stroke
				(width 0.1)
				(type default)
			)
			(layer "F.Fab")
		)
		(fp_line
			(start 0.12065 -0.3048)
			(end 0.67945 -0.3048)
			(stroke
				(width 0.1)
				(type default)
			)
			(layer "F.Fab")
		)
		(fp_line
			(start 0.67945 -0.3048)
			(end 0.67945 0.3048)
			(stroke
				(width 0.1)
				(type default)
			)
			(layer "F.Fab")
		)
		(fp_line
			(start -0.67945 -0.305054)
			(end -0.12065 -0.305054)
			(stroke
				(width 0.1)
				(type default)
			)
			(layer "F.Fab")
		)
		(fp_line
			(start -0.12065 -0.305054)
			(end -0.12065 -0.2794)
			(stroke
				(width 0.1)
				(type default)
			)
			(layer "F.Fab")
		)
		(pad "1" smd circle
			(at -0.40005 0 270)
			(size 0 0)
			(layers "F.Cu" "F.Mask" "F.Paste")
			(net "P1V25_SERDES_VDDPLL_PEX2")
		)
		(pad "2" smd circle
			(at 0.40005 0 270)
			(size 0 0)
			(layers "F.Cu" "F.Mask" "F.Paste")
			(net "P1V25_SERDES_VDDPLL_PEX2_C9")
		)
	)
	(footprint ""
		(layer "F.Cu")
		(at 471.418412 -555.019972 180)
		(property "Reference" "SCREW_SSD11_1"
			(at -5.6007 -1.402334 0)
			(unlocked yes)
			(layer "B.SilkS")
			(effects
				(font
					(size 0.7874 0.5842)
					(thickness 0.1524)
				)
				(justify mirror)
			)
		)
		(property "Value" ""
			(at 0 0 180)
			(layer "F.Fab")
			(effects
				(font
					(size 1.27 1.27)
				)
			)
		)
		(duplicate_pad_numbers_are_jumpers no)
		(pad "1" thru_hole circle
			(at 0 0 180)
			(size 0.4572 0.4572)
			(drill 0.2032)
			(layers "*.Cu" "*.Mask")
			(remove_unused_layers no)
			(net "Net_9152")
			(clearance 0.127)
			(thermal_gap 0.127)
			(padstack
				(mode front_inner_back)
				(layer "Inner"
					(shape circle)
					(size 0.4572 0.4572)
					(clearance 0.127)
				)
				(layer "B.Cu"
					(shape circle)
					(size 0.508 0.508)
					(clearance 0.1016)
				)
			)
		)
	)
	(footprint ""
		(layer "F.Cu")
		(at 127.947166 -112.755426 90)
		(property "Reference" "R5960"
			(at 0 0 90)
			(layer "F.SilkS")
			(hide yes)
			(effects
				(font
					(size 1.27 1.27)
				)
			)
		)
		(property "Value" ""
			(at 0 0 90)
			(layer "F.Fab")
			(effects
				(font
					(size 1.27 1.27)
				)
			)
		)
		(duplicate_pad_numbers_are_jumpers no)
		(fp_line
			(start 0.7874 -0.4064)
			(end 0.7874 0.4064)
			(stroke
				(width 0.1524)
				(type default)
			)
			(layer "F.SilkS")
		)
		(fp_line
			(start -0.7874 -0.4064)
			(end 0.7874 -0.4064)
			(stroke
				(width 0.1524)
				(type default)
			)
			(layer "F.SilkS")
		)
		(fp_line
			(start 0.7874 0.4064)
			(end -0.7874 0.4064)
			(stroke
				(width 0.1524)
				(type default)
			)
			(layer "F.SilkS")
		)
		(fp_line
			(start -0.7874 0.4064)
			(end -0.7874 -0.4064)
			(stroke
				(width 0.1524)
				(type default)
			)
			(layer "F.SilkS")
		)
		(fp_line
			(start -0.12065 -0.305054)
			(end -0.12065 -0.2794)
			(stroke
				(width 0.1)
				(type default)
			)
			(layer "F.Fab")
		)
		(fp_line
			(start -0.67945 -0.305054)
			(end -0.12065 -0.305054)
			(stroke
				(width 0.1)
				(type default)
			)
			(layer "F.Fab")
		)
		(fp_line
			(start 0.67945 -0.3048)
			(end 0.67945 0.3048)
			(stroke
				(width 0.1)
				(type default)
			)
			(layer "F.Fab")
		)
		(fp_line
			(start 0.12065 -0.3048)
			(end 0.67945 -0.3048)
			(stroke
				(width 0.1)
				(type default)
			)
			(layer "F.Fab")
		)
		(fp_line
			(start 0.12065 -0.2794)
			(end 0.12065 -0.3048)
			(stroke
				(width 0.1)
				(type default)
			)
			(layer "F.Fab")
		)
		(fp_line
			(start -0.12065 -0.2794)
			(end 0.12065 -0.2794)
			(stroke
				(width 0.1)
				(type default)
			)
			(layer "F.Fab")
		)
		(fp_line
			(start 0.120396 0.2794)
			(end -0.12065 0.2794)
			(stroke
				(width 0.1)
				(type default)
			)
			(layer "F.Fab")
		)
		(fp_line
			(start -0.12065 0.2794)
			(end -0.12065 0.3048)
			(stroke
				(width 0.1)
				(type default)
			)
			(layer "F.Fab")
		)
		(fp_line
			(start 0.67945 0.3048)
			(end 0.120396 0.3048)
			(stroke
				(width 0.1)
				(type default)
			)
			(layer "F.Fab")
		)
		(fp_line
			(start 0.120396 0.3048)
			(end 0.120396 0.2794)
			(stroke
				(width 0.1)
				(type default)
			)
			(layer "F.Fab")
		)
		(fp_line
			(start -0.12065 0.3048)
			(end -0.67945 0.3048)
			(stroke
				(width 0.1)
				(type default)
			)
			(layer "F.Fab")
		)
		(fp_line
			(start -0.67945 0.3048)
			(end -0.67945 -0.305054)
			(stroke
				(width 0.1)
				(type default)
			)
			(layer "F.Fab")
		)
		(pad "1" smd circle
			(at -0.40005 0 90)
			(size 0 0)
			(layers "F.Cu" "F.Mask" "F.Paste")
			(net "P5V_AUX")
		)
		(pad "2" smd circle
			(at 0.40005 0 90)
			(size 0 0)
			(layers "F.Cu" "F.Mask" "F.Paste")
			(net "P3V3_NIC2_PG_G2")
		)
	)
)
